(kicad_pcb
	(version 20260206)
	(generator "pcbnew")
	(generator_version "10.0")
	(general
		(thickness 1.6)
		(legacy_teardrops no)
	)
	(paper "A4")
	(title_block
		(title "04192023_DAF0TMB3IC0_F0TG_MB_C_brd_V02_OCP.brd")
		(comment 1 "Grand Teton / footprints 7443-7450 of 8354")
	)
	(layers
		(0 "F.Cu" signal "TOP")
		(4 "In1.Cu" signal "GND")
		(6 "In2.Cu" signal "IN1")
		(8 "In3.Cu" signal "GND1")
		(10 "In4.Cu" signal "IN2")
		(12 "In5.Cu" signal "GND2")
		(14 "In6.Cu" signal "IN3")
		(16 "In7.Cu" signal "GND3")
		(18 "In8.Cu" signal "VCC")
		(20 "In9.Cu" signal "VCC1")
		(22 "In10.Cu" signal "GND4")
		(24 "In11.Cu" signal "IN4")
		(26 "In12.Cu" signal "GND5")
		(28 "In13.Cu" signal "IN5")
		(30 "In14.Cu" signal "GND6")
		(32 "In15.Cu" signal "IN6")
		(34 "In16.Cu" signal "GND7")
		(2 "B.Cu" signal "BOTTOM")
		(9 "F.Adhes" user "F.Adhesive")
		(11 "B.Adhes" user "B.Adhesive")
		(13 "F.Paste" user "Package Geometry/Pastemask Top")
		(15 "B.Paste" user "Package Geometry/Pastemask Bottom")
		(5 "F.SilkS" user "Ref Des/Silkscreen Top")
		(7 "B.SilkS" user "Ref Des/Silkscreen Bottom")
		(1 "F.Mask" user "Board Geometry/Soldermask Top")
		(3 "B.Mask" user "Board Geometry/Soldermask Bottom")
		(17 "Dwgs.User" user "User.Drawings")
		(19 "Cmts.User" user "User.Comments")
		(21 "Eco1.User" user "User.Eco1")
		(23 "Eco2.User" user "User.Eco2")
		(25 "Edge.Cuts" user "Board Geometry/Outline")
		(27 "Margin" user)
		(31 "F.CrtYd" user "Package Geometry/Place Bound Top")
		(29 "B.CrtYd" user "Package Geometry/Place Bound Bottom")
		(35 "F.Fab" user "Ref Des/Assembly Top")
		(33 "B.Fab" user "Ref Des/Assembly Bottom")
	)
	(footprint ""
		(layer "B.Cu")
		(at 289.941 -426.466)
		(property "Reference" "R2674"
			(at 0 0 0)
			(layer "B.SilkS")
			(hide yes)
			(effects
				(font
					(size 1.27 1.27)
				)
				(justify mirror)
			)
		)
		(property "Value" ""
			(at 0 0 0)
			(layer "B.Fab")
			(effects
				(font
					(size 1.27 1.27)
				)
				(justify mirror)
			)
		)
		(duplicate_pad_numbers_are_jumpers no)
		(fp_line
			(start -0.7874 -0.4064)
			(end -0.7874 0.4064)
			(stroke
				(width 0.1524)
				(type default)
			)
			(layer "B.SilkS")
		)
		(fp_line
			(start -0.7874 0.4064)
			(end 0.7874 0.4064)
			(stroke
				(width 0.1524)
				(type default)
			)
			(layer "B.SilkS")
		)
		(fp_line
			(start 0.7874 -0.4064)
			(end -0.7874 -0.4064)
			(stroke
				(width 0.1524)
				(type default)
			)
			(layer "B.SilkS")
		)
		(fp_line
			(start 0.7874 0.4064)
			(end 0.7874 -0.4064)
			(stroke
				(width 0.1524)
				(type default)
			)
			(layer "B.SilkS")
		)
		(fp_line
			(start -0.67945 -0.3048)
			(end -0.67945 0.3048)
			(stroke
				(width 0.1)
				(type default)
			)
			(layer "B.Fab")
		)
		(fp_line
			(start -0.67945 0.3048)
			(end -0.120396 0.3048)
			(stroke
				(width 0.1)
				(type default)
			)
			(layer "B.Fab")
		)
		(fp_line
			(start -0.12065 -0.3048)
			(end -0.67945 -0.3048)
			(stroke
				(width 0.1)
				(type default)
			)
			(layer "B.Fab")
		)
		(fp_line
			(start -0.12065 -0.2794)
			(end -0.12065 -0.3048)
			(stroke
				(width 0.1)
				(type default)
			)
			(layer "B.Fab")
		)
		(fp_line
			(start -0.120396 0.2794)
			(end 0.12065 0.2794)
			(stroke
				(width 0.1)
				(type default)
			)
			(layer "B.Fab")
		)
		(fp_line
			(start -0.120396 0.3048)
			(end -0.120396 0.2794)
			(stroke
				(width 0.1)
				(type default)
			)
			(layer "B.Fab")
		)
		(fp_line
			(start 0.12065 -0.305054)
			(end 0.12065 -0.2794)
			(stroke
				(width 0.1)
				(type default)
			)
			(layer "B.Fab")
		)
		(fp_line
			(start 0.12065 -0.2794)
			(end -0.12065 -0.2794)
			(stroke
				(width 0.1)
				(type default)
			)
			(layer "B.Fab")
		)
		(fp_line
			(start 0.12065 0.2794)
			(end 0.12065 0.3048)
			(stroke
				(width 0.1)
				(type default)
			)
			(layer "B.Fab")
		)
		(fp_line
			(start 0.12065 0.3048)
			(end 0.67945 0.3048)
			(stroke
				(width 0.1)
				(type default)
			)
			(layer "B.Fab")
		)
		(fp_line
			(start 0.67945 -0.305054)
			(end 0.12065 -0.305054)
			(stroke
				(width 0.1)
				(type default)
			)
			(layer "B.Fab")
		)
		(fp_line
			(start 0.67945 0.3048)
			(end 0.67945 -0.305054)
			(stroke
				(width 0.1)
				(type default)
			)
			(layer "B.Fab")
		)
		(pad "1" smd circle
			(at 0.40005 0 180)
			(size 0 0)
			(layers "B.Cu" "B.Mask" "B.Paste")
			(net "I3C_BMC_SWB_BUF_R_SDA")
		)
		(pad "2" smd circle
			(at -0.40005 0 180)
			(size 0 0)
			(layers "B.Cu" "B.Mask" "B.Paste")
			(net "I3C_BMC_SWB_BUF_SDA")
		)
	)
	(footprint ""
		(layer "B.Cu")
		(at 216.027 -338.455 -90)
		(property "Reference" "R6750"
			(at 0 0 90)
			(layer "B.SilkS")
			(hide yes)
			(effects
				(font
					(size 1.27 1.27)
				)
				(justify mirror)
			)
		)
		(property "Value" ""
			(at 0 0 90)
			(layer "B.Fab")
			(effects
				(font
					(size 1.27 1.27)
				)
				(justify mirror)
			)
		)
		(duplicate_pad_numbers_are_jumpers no)
		(fp_line
			(start -0.32512 0.175006)
			(end 0.32512 0.175006)
			(stroke
				(width 0.1)
				(type default)
			)
			(layer "B.Fab")
		)
		(fp_line
			(start 0.32512 0.175006)
			(end 0.32512 -0.175006)
			(stroke
				(width 0.1)
				(type default)
			)
			(layer "B.Fab")
		)
		(fp_line
			(start -0.32512 -0.175006)
			(end -0.32512 0.175006)
			(stroke
				(width 0.1)
				(type default)
			)
			(layer "B.Fab")
		)
		(fp_line
			(start 0.32512 -0.175006)
			(end -0.32512 -0.175006)
			(stroke
				(width 0.1)
				(type default)
			)
			(layer "B.Fab")
		)
		(pad "1" smd rect
			(at 0.2667 0 90)
			(size 0.3048 0.381)
			(layers "B.Cu" "B.Mask" "B.Paste")
			(net "P1V8_CPU1_RT_1D")
		)
		(pad "2" smd rect
			(at -0.2667 0 270)
			(size 0.3048 0.381)
			(layers "B.Cu" "B.Mask" "B.Paste")
			(net "SMB_RT_CPU1_P3_R_SDA")
		)
	)
	(footprint ""
		(layer "B.Cu")
		(at 349.105982 -395.148562 90)
		(property "Reference" "C624"
			(at 0 0 90)
			(layer "B.SilkS")
			(hide yes)
			(effects
				(font
					(size 1.27 1.27)
				)
				(justify mirror)
			)
		)
		(property "Value" ""
			(at 0 0 90)
			(layer "B.Fab")
			(effects
				(font
					(size 1.27 1.27)
				)
				(justify mirror)
			)
		)
		(duplicate_pad_numbers_are_jumpers no)
		(fp_line
			(start 0.299974 -0.150114)
			(end -0.299974 -0.150114)
			(stroke
				(width 0.1)
				(type default)
			)
			(layer "B.Fab")
		)
		(fp_line
			(start -0.299974 -0.150114)
			(end -0.299974 0.150114)
			(stroke
				(width 0.1)
				(type default)
			)
			(layer "B.Fab")
		)
		(fp_line
			(start 0.299974 0.150114)
			(end 0.299974 -0.150114)
			(stroke
				(width 0.1)
				(type default)
			)
			(layer "B.Fab")
		)
		(fp_line
			(start -0.299974 0.150114)
			(end 0.299974 0.150114)
			(stroke
				(width 0.1)
				(type default)
			)
			(layer "B.Fab")
		)
		(pad "1" smd rect
			(at 0.2667 0 270)
			(size 0.3048 0.381)
			(layers "B.Cu" "B.Mask" "B.Paste")
			(net "P0V9_CPU0_RT1_2A_2D")
		)
		(pad "2" smd rect
			(at -0.2667 0 270)
			(size 0.3048 0.381)
			(layers "B.Cu" "B.Mask" "B.Paste")
			(net "GND")
		)
	)
	(footprint ""
		(layer "B.Cu")
		(at 188.838078 -97.085912 -90)
		(property "Reference" "R261"
			(at 0 0 90)
			(layer "B.SilkS")
			(hide yes)
			(effects
				(font
					(size 1.27 1.27)
				)
				(justify mirror)
			)
		)
		(property "Value" ""
			(at 0 0 90)
			(layer "B.Fab")
			(effects
				(font
					(size 1.27 1.27)
				)
				(justify mirror)
			)
		)
		(duplicate_pad_numbers_are_jumpers no)
		(fp_line
			(start -0.7874 0.4064)
			(end 0.7874 0.4064)
			(stroke
				(width 0.1524)
				(type default)
			)
			(layer "B.SilkS")
		)
		(fp_line
			(start 0.7874 0.4064)
			(end 0.7874 -0.4064)
			(stroke
				(width 0.1524)
				(type default)
			)
			(layer "B.SilkS")
		)
		(fp_line
			(start -0.7874 -0.4064)
			(end -0.7874 0.4064)
			(stroke
				(width 0.1524)
				(type default)
			)
			(layer "B.SilkS")
		)
		(fp_line
			(start 0.7874 -0.4064)
			(end -0.7874 -0.4064)
			(stroke
				(width 0.1524)
				(type default)
			)
			(layer "B.SilkS")
		)
		(fp_line
			(start -0.67945 0.3048)
			(end -0.120396 0.3048)
			(stroke
				(width 0.1)
				(type default)
			)
			(layer "B.Fab")
		)
		(fp_line
			(start -0.120396 0.3048)
			(end -0.120396 0.2794)
			(stroke
				(width 0.1)
				(type default)
			)
			(layer "B.Fab")
		)
		(fp_line
			(start 0.12065 0.3048)
			(end 0.67945 0.3048)
			(stroke
				(width 0.1)
				(type default)
			)
			(layer "B.Fab")
		)
		(fp_line
			(start 0.67945 0.3048)
			(end 0.67945 -0.305054)
			(stroke
				(width 0.1)
				(type default)
			)
			(layer "B.Fab")
		)
		(fp_line
			(start -0.120396 0.2794)
			(end 0.12065 0.2794)
			(stroke
				(width 0.1)
				(type default)
			)
			(layer "B.Fab")
		)
		(fp_line
			(start 0.12065 0.2794)
			(end 0.12065 0.3048)
			(stroke
				(width 0.1)
				(type default)
			)
			(layer "B.Fab")
		)
		(fp_line
			(start -0.12065 -0.2794)
			(end -0.12065 -0.3048)
			(stroke
				(width 0.1)
				(type default)
			)
			(layer "B.Fab")
		)
		(fp_line
			(start 0.12065 -0.2794)
			(end -0.12065 -0.2794)
			(stroke
				(width 0.1)
				(type default)
			)
			(layer "B.Fab")
		)
		(fp_line
			(start -0.67945 -0.3048)
			(end -0.67945 0.3048)
			(stroke
				(width 0.1)
				(type default)
			)
			(layer "B.Fab")
		)
		(fp_line
			(start -0.12065 -0.3048)
			(end -0.67945 -0.3048)
			(stroke
				(width 0.1)
				(type default)
			)
			(layer "B.Fab")
		)
		(fp_line
			(start 0.12065 -0.305054)
			(end 0.12065 -0.2794)
			(stroke
				(width 0.1)
				(type default)
			)
			(layer "B.Fab")
		)
		(fp_line
			(start 0.67945 -0.305054)
			(end 0.12065 -0.305054)
			(stroke
				(width 0.1)
				(type default)
			)
			(layer "B.Fab")
		)
		(pad "1" smd circle
			(at 0.40005 0 90)
			(size 0 0)
			(layers "B.Cu" "B.Mask" "B.Paste")
			(net "CPU1_SP5R2")
		)
		(pad "2" smd circle
			(at -0.40005 0 90)
			(size 0 0)
			(layers "B.Cu" "B.Mask" "B.Paste")
			(net "FM_CPU1_SP5R2")
		)
	)
	(footprint ""
		(layer "B.Cu")
		(at 348.786958 -252.54331 180)
		(property "Reference" "C2518"
			(at 0 0 0)
			(layer "B.SilkS")
			(hide yes)
			(effects
				(font
					(size 1.27 1.27)
				)
				(justify mirror)
			)
		)
		(property "Value" ""
			(at 0 0 0)
			(layer "B.Fab")
			(effects
				(font
					(size 1.27 1.27)
				)
				(justify mirror)
			)
		)
		(duplicate_pad_numbers_are_jumpers no)
		(fp_line
			(start 0.7874 0.4064)
			(end 0.7874 -0.4064)
			(stroke
				(width 0.1524)
				(type default)
			)
			(layer "B.SilkS")
		)
		(fp_line
			(start 0.7874 -0.4064)
			(end -0.7874 -0.4064)
			(stroke
				(width 0.1524)
				(type default)
			)
			(layer "B.SilkS")
		)
		(fp_line
			(start -0.7874 0.4064)
			(end 0.7874 0.4064)
			(stroke
				(width 0.1524)
				(type default)
			)
			(layer "B.SilkS")
		)
		(fp_line
			(start -0.7874 -0.4064)
			(end -0.7874 0.4064)
			(stroke
				(width 0.1524)
				(type default)
			)
			(layer "B.SilkS")
		)
		(fp_line
			(start 0.67945 0.3048)
			(end 0.67945 -0.305054)
			(stroke
				(width 0.1)
				(type default)
			)
			(layer "B.Fab")
		)
		(fp_line
			(start 0.67945 -0.305054)
			(end 0.12065 -0.305054)
			(stroke
				(width 0.1)
				(type default)
			)
			(layer "B.Fab")
		)
		(fp_line
			(start 0.12065 0.3048)
			(end 0.67945 0.3048)
			(stroke
				(width 0.1)
				(type default)
			)
			(layer "B.Fab")
		)
		(fp_line
			(start 0.12065 0.2794)
			(end 0.12065 0.3048)
			(stroke
				(width 0.1)
				(type default)
			)
			(layer "B.Fab")
		)
		(fp_line
			(start 0.12065 -0.2794)
			(end -0.12065 -0.2794)
			(stroke
				(width 0.1)
				(type default)
			)
			(layer "B.Fab")
		)
		(fp_line
			(start 0.12065 -0.305054)
			(end 0.12065 -0.2794)
			(stroke
				(width 0.1)
				(type default)
			)
			(layer "B.Fab")
		)
		(fp_line
			(start -0.120396 0.3048)
			(end -0.120396 0.2794)
			(stroke
				(width 0.1)
				(type default)
			)
			(layer "B.Fab")
		)
		(fp_line
			(start -0.120396 0.2794)
			(end 0.12065 0.2794)
			(stroke
				(width 0.1)
				(type default)
			)
			(layer "B.Fab")
		)
		(fp_line
			(start -0.12065 -0.2794)
			(end -0.12065 -0.3048)
			(stroke
				(width 0.1)
				(type default)
			)
			(layer "B.Fab")
		)
		(fp_line
			(start -0.12065 -0.3048)
			(end -0.67945 -0.3048)
			(stroke
				(width 0.1)
				(type default)
			)
			(layer "B.Fab")
		)
		(fp_line
			(start -0.67945 0.3048)
			(end -0.120396 0.3048)
			(stroke
				(width 0.1)
				(type default)
			)
			(layer "B.Fab")
		)
		(fp_line
			(start -0.67945 -0.3048)
			(end -0.67945 0.3048)
			(stroke
				(width 0.1)
				(type default)
			)
			(layer "B.Fab")
		)
		(pad "1" smd circle
			(at 0.40005 0)
			(size 0 0)
			(layers "B.Cu" "B.Mask" "B.Paste")
			(net "PVDD18_S5_P0")
		)
		(pad "2" smd circle
			(at -0.40005 0)
			(size 0 0)
			(layers "B.Cu" "B.Mask" "B.Paste")
			(net "GND")
		)
	)
	(footprint ""
		(layer "B.Cu")
		(at 344.446098 -396.393162 -90)
		(property "Reference" "C599"
			(at 0 0 90)
			(layer "B.SilkS")
			(hide yes)
			(effects
				(font
					(size 1.27 1.27)
				)
				(justify mirror)
			)
		)
		(property "Value" ""
			(at 0 0 90)
			(layer "B.Fab")
			(effects
				(font
					(size 1.27 1.27)
				)
				(justify mirror)
			)
		)
		(duplicate_pad_numbers_are_jumpers no)
		(fp_line
			(start -0.299974 0.150114)
			(end 0.299974 0.150114)
			(stroke
				(width 0.1)
				(type default)
			)
			(layer "B.Fab")
		)
		(fp_line
			(start 0.299974 0.150114)
			(end 0.299974 -0.150114)
			(stroke
				(width 0.1)
				(type default)
			)
			(layer "B.Fab")
		)
		(fp_line
			(start -0.299974 -0.150114)
			(end -0.299974 0.150114)
			(stroke
				(width 0.1)
				(type default)
			)
			(layer "B.Fab")
		)
		(fp_line
			(start 0.299974 -0.150114)
			(end -0.299974 -0.150114)
			(stroke
				(width 0.1)
				(type default)
			)
			(layer "B.Fab")
		)
		(pad "1" smd rect
			(at 0.2667 0 90)
			(size 0.3048 0.381)
			(layers "B.Cu" "B.Mask" "B.Paste")
			(net "P1V8_CPU0_RT1_1A")
		)
		(pad "2" smd rect
			(at -0.2667 0 90)
			(size 0.3048 0.381)
			(layers "B.Cu" "B.Mask" "B.Paste")
			(net "GND")
		)
	)
	(footprint ""
		(layer "B.Cu")
		(at 76.453746 -336.05216 -90)
		(property "Reference" "PR257"
			(at 0 0 90)
			(layer "B.SilkS")
			(hide yes)
			(effects
				(font
					(size 1.27 1.27)
				)
				(justify mirror)
			)
		)
		(property "Value" ""
			(at 0 0 90)
			(layer "B.Fab")
			(effects
				(font
					(size 1.27 1.27)
				)
				(justify mirror)
			)
		)
		(duplicate_pad_numbers_are_jumpers no)
		(fp_line
			(start -0.7874 0.4064)
			(end 0.7874 0.4064)
			(stroke
				(width 0.1524)
				(type default)
			)
			(layer "B.SilkS")
		)
		(fp_line
			(start 0.7874 0.4064)
			(end 0.7874 -0.4064)
			(stroke
				(width 0.1524)
				(type default)
			)
			(layer "B.SilkS")
		)
		(fp_line
			(start -0.7874 -0.4064)
			(end -0.7874 0.4064)
			(stroke
				(width 0.1524)
				(type default)
			)
			(layer "B.SilkS")
		)
		(fp_line
			(start 0.7874 -0.4064)
			(end -0.7874 -0.4064)
			(stroke
				(width 0.1524)
				(type default)
			)
			(layer "B.SilkS")
		)
		(fp_line
			(start -0.67945 0.3048)
			(end -0.120396 0.3048)
			(stroke
				(width 0.1)
				(type default)
			)
			(layer "B.Fab")
		)
		(fp_line
			(start -0.120396 0.3048)
			(end -0.120396 0.2794)
			(stroke
				(width 0.1)
				(type default)
			)
			(layer "B.Fab")
		)
		(fp_line
			(start 0.12065 0.3048)
			(end 0.67945 0.3048)
			(stroke
				(width 0.1)
				(type default)
			)
			(layer "B.Fab")
		)
		(fp_line
			(start 0.67945 0.3048)
			(end 0.67945 -0.305054)
			(stroke
				(width 0.1)
				(type default)
			)
			(layer "B.Fab")
		)
		(fp_line
			(start -0.120396 0.2794)
			(end 0.12065 0.2794)
			(stroke
				(width 0.1)
				(type default)
			)
			(layer "B.Fab")
		)
		(fp_line
			(start 0.12065 0.2794)
			(end 0.12065 0.3048)
			(stroke
				(width 0.1)
				(type default)
			)
			(layer "B.Fab")
		)
		(fp_line
			(start -0.12065 -0.2794)
			(end -0.12065 -0.3048)
			(stroke
				(width 0.1)
				(type default)
			)
			(layer "B.Fab")
		)
		(fp_line
			(start 0.12065 -0.2794)
			(end -0.12065 -0.2794)
			(stroke
				(width 0.1)
				(type default)
			)
			(layer "B.Fab")
		)
		(fp_line
			(start -0.67945 -0.3048)
			(end -0.67945 0.3048)
			(stroke
				(width 0.1)
				(type default)
			)
			(layer "B.Fab")
		)
		(fp_line
			(start -0.12065 -0.3048)
			(end -0.67945 -0.3048)
			(stroke
				(width 0.1)
				(type default)
			)
			(layer "B.Fab")
		)
		(fp_line
			(start 0.12065 -0.305054)
			(end 0.12065 -0.2794)
			(stroke
				(width 0.1)
				(type default)
			)
			(layer "B.Fab")
		)
		(fp_line
			(start 0.67945 -0.305054)
			(end 0.12065 -0.305054)
			(stroke
				(width 0.1)
				(type default)
			)
			(layer "B.Fab")
		)
		(pad "1" smd circle
			(at 0.40005 0 90)
			(size 0 0)
			(layers "B.Cu" "B.Mask" "B.Paste")
			(net "PVDDCR_CPU1_P1_PVCC")
		)
		(pad "2" smd circle
			(at -0.40005 0 90)
			(size 0 0)
			(layers "B.Cu" "B.Mask" "B.Paste")
			(net "PVDDCR_CPU1_P1_VCC2")
		)
	)
	(footprint ""
		(layer "B.Cu")
		(at 90.503502 -207.41005 90)
		(property "Reference" "R862"
			(at 0 0 90)
			(layer "B.SilkS")
			(hide yes)
			(effects
				(font
					(size 1.27 1.27)
				)
				(justify mirror)
			)
		)
		(property "Value" ""
			(at 0 0 90)
			(layer "B.Fab")
			(effects
				(font
					(size 1.27 1.27)
				)
				(justify mirror)
			)
		)
		(duplicate_pad_numbers_are_jumpers no)
		(fp_line
			(start 0.7874 -0.4064)
			(end -0.7874 -0.4064)
			(stroke
				(width 0.1524)
				(type default)
			)
			(layer "B.SilkS")
		)
		(fp_line
			(start -0.7874 -0.4064)
			(end -0.7874 0.4064)
			(stroke
				(width 0.1524)
				(type default)
			)
			(layer "B.SilkS")
		)
		(fp_line
			(start 0.7874 0.4064)
			(end 0.7874 -0.4064)
			(stroke
				(width 0.1524)
				(type default)
			)
			(layer "B.SilkS")
		)
		(fp_line
			(start -0.7874 0.4064)
			(end 0.7874 0.4064)
			(stroke
				(width 0.1524)
				(type default)
			)
			(layer "B.SilkS")
		)
		(fp_line
			(start 0.67945 -0.305054)
			(end 0.12065 -0.305054)
			(stroke
				(width 0.1)
				(type default)
			)
			(layer "B.Fab")
		)
		(fp_line
			(start 0.12065 -0.305054)
			(end 0.12065 -0.2794)
			(stroke
				(width 0.1)
				(type default)
			)
			(layer "B.Fab")
		)
		(fp_line
			(start -0.12065 -0.3048)
			(end -0.67945 -0.3048)
			(stroke
				(width 0.1)
				(type default)
			)
			(layer "B.Fab")
		)
		(fp_line
			(start -0.67945 -0.3048)
			(end -0.67945 0.3048)
			(stroke
				(width 0.1)
				(type default)
			)
			(layer "B.Fab")
		)
		(fp_line
			(start 0.12065 -0.2794)
			(end -0.12065 -0.2794)
			(stroke
				(width 0.1)
				(type default)
			)
			(layer "B.Fab")
		)
		(fp_line
			(start -0.12065 -0.2794)
			(end -0.12065 -0.3048)
			(stroke
				(width 0.1)
				(type default)
			)
			(layer "B.Fab")
		)
		(fp_line
			(start 0.12065 0.2794)
			(end 0.12065 0.3048)
			(stroke
				(width 0.1)
				(type default)
			)
			(layer "B.Fab")
		)
		(fp_line
			(start -0.120396 0.2794)
			(end 0.12065 0.2794)
			(stroke
				(width 0.1)
				(type default)
			)
			(layer "B.Fab")
		)
		(fp_line
			(start 0.67945 0.3048)
			(end 0.67945 -0.305054)
			(stroke
				(width 0.1)
				(type default)
			)
			(layer "B.Fab")
		)
		(fp_line
			(start 0.12065 0.3048)
			(end 0.67945 0.3048)
			(stroke
				(width 0.1)
				(type default)
			)
			(layer "B.Fab")
		)
		(fp_line
			(start -0.120396 0.3048)
			(end -0.120396 0.2794)
			(stroke
				(width 0.1)
				(type default)
			)
			(layer "B.Fab")
		)
		(fp_line
			(start -0.67945 0.3048)
			(end -0.120396 0.3048)
			(stroke
				(width 0.1)
				(type default)
			)
			(layer "B.Fab")
		)
		(pad "1" smd circle
			(at 0.40005 0 270)
			(size 0 0)
			(layers "B.Cu" "B.Mask" "B.Paste")
			(net "CPU1_XTRIG_R2_L6")
		)
		(pad "2" smd circle
			(at -0.40005 0 270)
			(size 0 0)
			(layers "B.Cu" "B.Mask" "B.Paste")
			(net "CPU1_XTRIG_L6")
		)
	)
)
